%FSTAX23Y23*%
%MOIN*%
%SFA1B1*%

%IPPOS*%
%ADD12C,0.003940*%
%ADD174C,0.000000*%
%LNgrandmaster-1*%
%LPD*%
G54D12*
X02287Y00293D02*
D01*
X02287Y00295*
X02287Y00298*
X02286Y00301*
X02285Y00303*
X02285Y00306*
X02284Y00308*
X02283Y0031*
X02281Y00313*
X0228Y00315*
X02278Y00317*
X02276Y00319*
X02275Y00321*
X02273Y00322*
X0227Y00324*
X02268Y00325*
X02266Y00326*
X02264Y00327*
X02261Y00328*
X02259Y00329*
X02256Y0033*
X02253Y0033*
X02251Y0033*
X02248*
X02246Y0033*
X02243Y0033*
X0224Y00329*
X02238Y00328*
X02235Y00327*
X02233Y00326*
X02231Y00325*
X02229Y00324*
X02226Y00322*
X02224Y00321*
X02223Y00319*
X02221Y00317*
X02219Y00315*
X02218Y00313*
X02216Y0031*
X02215Y00308*
X02214Y00306*
X02214Y00303*
X02213Y00301*
X02212Y00298*
X02212Y00295*
X02212Y00293*
X01771Y0043D02*
D01*
X01771Y00435*
X0177Y0044*
X0177Y00445*
X01768Y00449*
X01767Y00454*
X01765Y00459*
X01763Y00463*
X0176Y00468*
X01757Y00472*
X01754Y00476*
X01751Y0048*
X01747Y00483*
X01744Y00486*
X01739Y00489*
X01735Y00492*
X01731Y00494*
X01726Y00496*
X01722Y00498*
X01717Y00499*
X01712Y005*
X01707Y00501*
X01702Y00501*
X01697*
X01692Y00501*
X01687Y005*
X01682Y00499*
X01677Y00498*
X01672Y00496*
X01668Y00494*
X01663Y00492*
X01659Y00489*
X01655Y00486*
X01651Y00483*
X01648Y0048*
X01644Y00476*
X01641Y00472*
X01638Y00468*
X01636Y00463*
X01634Y00459*
X01632Y00454*
X0163Y00449*
X01629Y00445*
X01628Y0044*
X01628Y00435*
X01627Y0043*
X02287Y00019D02*
Y00293D01*
X02212Y00019D02*
Y00293D01*
X03102Y0D02*
X03122Y00019D01*
X02287D02*
X02307Y0D01*
X02192D02*
X02212Y00019D01*
X01771D02*
X01791Y0D01*
X03122Y00019D02*
Y00501D01*
X02307Y0D02*
X03102D01*
X01791D02*
X02192D01*
X01771Y00019D02*
Y0043D01*
X01627Y00177D02*
Y0043D01*
X01312Y00177D02*
X01627D01*
X01312D02*
Y00501D01*
X0059D02*
X01312D01*
X0059Y00177D02*
Y00501D01*
X0Y00177D02*
X0059D01*
X0D02*
Y04375D01*
X03122Y00501D02*
X07087D01*
Y04375D02*
Y00501D01*
X0Y04375D02*
X07087D01*
G54D174*
X05954Y03878D02*
Y03997D01*
X05915D02*
X05954D01*
X05915Y03878D02*
Y03997D01*
Y03878D02*
X05954D01*
X0606Y04075D02*
X06178D01*
X0606Y04036D02*
Y04075D01*
Y04036D02*
X06178D01*
Y04075*
X0605Y03839D02*
X06188D01*
X0605Y038D02*
Y03839D01*
Y038D02*
X06188D01*
Y03839*
M02*